# BASEBOARD_FAB2 (Tioga Pass) — schematic netlist excerpt (pin names and nets, part order shuffled) for the footprints in the layout excerpt that follows; sources: Cadence DE-HDL packaged netlist, KiCad conversion of Wiwynn_Tioga_Pass_MB.brd

J6U1  SCONN288_H44441003  SCONN  pkg PIP  page 46
  \12v\(1)  = P12V_NVDIMM_ABC
  VSS(93)  = GND
  DQ(4)  = M_B_DQ<4>
  VSS(92)  = GND
  DQ(0)  = M_B_DQ<0>
  VSS(91)  = GND
  DQS9P  = M_B_DQS_DP<9>
  DQS9N  = M_B_DQS_DN<9>
  VSS(90)  = GND
  DQ(6)  = M_B_DQ<6>
  VSS(89)  = GND
  DQ(2)  = M_B_DQ<2>
  VSS(88)  = GND
  DQ(12)  = M_B_DQ<12>
  VSS(87)  = GND
  DQ(8)  = M_B_DQ<8>
  VSS(86)  = GND
  DQS10P  = M_B_DQS_DP<10>
  DQS10N  = M_B_DQS_DN<10>
  VSS(85)  = GND
  DQ(14)  = M_B_DQ<14>
  VSS(84)  = GND
  DQ(10)  = M_B_DQ<10>
  VSS(83)  = GND
  DQ(20)  = M_B_DQ<20>
  VSS(82)  = GND
  DQ(16)  = M_B_DQ<16>
  VSS(81)  = GND
  DQS11P  = M_B_DQS_DP<11>
  DQS11N  = M_B_DQS_DN<11>
  VSS(80)  = GND
  DQ(22)  = M_B_DQ<22>
  VSS(79)  = GND
  DQ(18)  = M_B_DQ<18>
  VSS(78)  = GND
  DQ(28)  = M_B_DQ<28>
  VSS(77)  = GND
  DQ(24)  = M_B_DQ<24>
  VSS(76)  = GND
  DQS12P  = M_B_DQS_DP<12>
  DQS12N  = M_B_DQS_DN<12>
  VSS(75)  = GND
  DQ(30)  = M_B_DQ<30>
  VSS(74)  = GND
  DQ(26)  = M_B_DQ<26>
  VSS(73)  = GND
  CB(4)  = M_B_ECC<4>
  VSS(72)  = GND
  CB(0)  = M_B_ECC<0>
  VSS(71)  = GND
  DQS17P  = M_B_DQS_DP<17>
  DQS17N  = M_B_DQS_DN<17>
  VSS(70)  = GND
  CB(6)  = M_B_ECC<6>
  VSS(69)  = GND
  CB(2)  = M_B_ECC<2>
  VSS(68)  = GND
  RESET_N  = M_ABC_RST_N
  VDD(25)  = PVDDQ_ABC
  CKE(0)  = M_B_CKE<2>
  VDD(24)  = PVDDQ_ABC
  ACT_N  = M_B_ACT_N
  BG(0)  = M_B_BG<0>
  VDD(23)  = PVDDQ_ABC
  A12  = M_B_MA<12>
  A9  = M_B_MA<9>
  VDD(22)  = PVDDQ_ABC
  A8  = M_B_MA<8>
  A6  = M_B_MA<6>
  VDD(21)  = PVDDQ_ABC
  A3  = M_B_MA<3>
  A1  = M_B_MA<1>
  VDD(20)  = PVDDQ_ABC
  CK0P  = M_B_CLK_DP<2>
  CK0N  = M_B_CLK_DN<2>
  VDD(19)  = PVDDQ_ABC
  VTT(1)  = PVTT_ABC
  EVENT_N  = FM_DIMM_EVENT_COD_N
  A0  = M_B_MA<0>
  VDD(18)  = PVDDQ_ABC
  BA(0)  = M_B_BA<0>
  A16_RAS_N  = M_B_MA<16>
  VDD(17)  = PVDDQ_ABC
  S0_N  = M_B_CS_N<4>
  VDD(16)  = PVDDQ_ABC
  A15_CAS_N  = M_B_MA<15>
  ODT(0)  = M_B_ODT<2>
  VDD(15)  = PVDDQ_ABC
  S1_N  = M_B_CS_N<5>
  VDD(14)  = PVDDQ_ABC
  ODT(1)  = M_B_ODT<3>
  VDD(13)  = PVDDQ_ABC
  S2_N_C(0)  = M_B_CS_N<6>
  VSS(67)  = GND
  DQ(36)  = M_B_DQ<36>
  VSS(66)  = GND
  DQ(32)  = M_B_DQ<32>
  VSS(65)  = GND
  DQS13P  = M_B_DQS_DP<13>
  DQS13N  = M_B_DQS_DN<13>
  VSS(64)  = GND
  DQ(38)  = M_B_DQ<38>
  VSS(63)  = GND
  DQ(34)  = M_B_DQ<34>
  VSS(62)  = GND
  DQ(44)  = M_B_DQ<44>
  VSS(61)  = GND
  DQ(40)  = M_B_DQ<40>
  VSS(60)  = GND
  DQS14P  = M_B_DQS_DP<14>
  DQS14N  = M_B_DQS_DN<14>
  VSS(59)  = GND
  DQ(46)  = M_B_DQ<46>
  VSS(58)  = GND
  DQ(42)  = M_B_DQ<42>
  VSS(57)  = GND
  DQ(52)  = M_B_DQ<52>
  VSS(56)  = GND
  DQ(48)  = M_B_DQ<48>
  VSS(55)  = GND
  DQS15P  = M_B_DQS_DP<15>
  DQS15N  = M_B_DQS_DN<15>
  VSS(54)  = GND
  DQ(54)  = M_B_DQ<54>
  VSS(53)  = GND
  DQ(50)  = M_B_DQ<50>
  VSS(52)  = GND
  DQ(60)  = M_B_DQ<60>
  VSS(51)  = GND
  DQ(56)  = M_B_DQ<56>
  VSS(50)  = GND
  DQS16P  = M_B_DQS_DP<16>
  DQS16N  = M_B_DQS_DN<16>
  VSS(49)  = GND
  DQ(62)  = M_B_DQ<62>
  VSS(48)  = GND
  DQ(58)  = M_B_DQ<58>
  VSS(47)  = GND
  SA(0)  = PVPP_ABC
  SA(1)  = PVPP_ABC
  SCL  = SMB_DDR_ABC_VPP_SCL
  VPP(4)  = PVPP_ABC
  VPP(3)  = PVPP_ABC
  RFU(2)  = TP_CH_B_DIMM_B1_RFU_2
  \12v\(0)  = P12V_NVDIMM_ABC
  VREFCA  = M_B_VREF
  VSS(46)  = GND
  DQ(5)  = M_B_DQ<5>
  VSS(45)  = GND
  DQ(1)  = M_B_DQ<1>
  VSS(44)  = GND
  DQS0N  = M_B_DQS_DN<0>
  DQS0P  = M_B_DQS_DP<0>
  VSS(43)  = GND
  DQ(7)  = M_B_DQ<7>
  VSS(42)  = GND
  DQ(3)  = M_B_DQ<3>
  VSS(41)  = GND
  DQ(13)  = M_B_DQ<13>
  VSS(40)  = GND
  DQ(9)  = M_B_DQ<9>
  VSS(39)  = GND
  DQS1N  = M_B_DQS_DN<1>
  DQS1P  = M_B_DQS_DP<1>
  VSS(38)  = GND
  DQ(15)  = M_B_DQ<15>
  VSS(37)  = GND
  DQ(11)  = M_B_DQ<11>
  VSS(36)  = GND
  DQ(21)  = M_B_DQ<21>
  VSS(35)  = GND
  DQ(17)  = M_B_DQ<17>
  VSS(34)  = GND
  DQS2N  = M_B_DQS_DN<2>
  DQS2P  = M_B_DQS_DP<2>
  VSS(33)  = GND
  DQ(23)  = M_B_DQ<23>
  VSS(32)  = GND
  DQ(19)  = M_B_DQ<19>
  VSS(31)  = GND
  DQ(29)  = M_B_DQ<29>
  VSS(30)  = GND
  DQ(25)  = M_B_DQ<25>
  VSS(29)  = GND
  DQS3N  = M_B_DQS_DN<3>
  DQS3P  = M_B_DQS_DP<3>
  VSS(28)  = GND
  DQ(31)  = M_B_DQ<31>
  VSS(27)  = GND
  DQ(27)  = M_B_DQ<27>
  VSS(26)  = GND
  CB(5)  = M_B_ECC<5>
  VSS(25)  = GND
  CB(1)  = M_B_ECC<1>
  VSS(24)  = GND
  DQS8N  = M_B_DQS_DN<8>
  DQS8P  = M_B_DQS_DP<8>
  VSS(23)  = GND
  CB(7)  = M_B_ECC<7>
  VSS(22)  = GND
  CB(3)  = M_B_ECC<3>
  VSS(21)  = GND
  CKE(1)  = M_B_CKE<3>
  VDD(12)  = PVDDQ_ABC
  RFU(0)  = TP_CH_B_DIMM_B1_RFU_0
  VDD(11)  = PVDDQ_ABC
  BG(1)  = M_B_BG<1>
  ALERT_N  = M_B_ALERT_N
  VDD(10)  = PVDDQ_ABC
  A11  = M_B_MA<11>
  A7  = M_B_MA<7>
  VDD(9)  = PVDDQ_ABC
  A5  = M_B_MA<5>
  A4  = M_B_MA<4>
  VDD(8)  = PVDDQ_ABC
  A2  = M_B_MA<2>
  VDD(7)  = PVDDQ_ABC
  CK1P  = M_B_CLK_DP<3>
  CK1N  = M_B_CLK_DN<3>
  VDD(6)  = PVDDQ_ABC
  VTT(0)  = PVTT_ABC
  PAR  = M_B_PAR
  VDD(5)  = PVDDQ_ABC
  BA(1)  = M_B_BA<1>
  A10  = M_B_MA<10>
  VDD(4)  = PVDDQ_ABC
  RFU(1)  = TP_CH_B_DIMM_B1_RFU_1
  A14_WE_N  = M_B_MA<14>
  VDD(3)  = PVDDQ_ABC
  SAVE_N_NC  = FM_ADR_COMPLETE_ABC_N
  VDD(2)  = PVDDQ_ABC
  A13  = M_B_MA<13>
  VDD(1)  = PVDDQ_ABC
  A17  = M_B_MA<17>
  C(2)  = M_B_C<2>
  VDD(0)  = PVDDQ_ABC
  S3_N_C(1)  = M_B_CS_N<7>
  SA(2)  = GND
  VSS(20)  = GND
  DQ(37)  = M_B_DQ<37>
  VSS(19)  = GND
  DQ(33)  = M_B_DQ<33>
  VSS(18)  = GND
  DQS4N  = M_B_DQS_DN<4>
  DQS4P  = M_B_DQS_DP<4>
  VSS(17)  = GND
  DQ(39)  = M_B_DQ<39>
  VSS(16)  = GND
  DQ(35)  = M_B_DQ<35>
  VSS(15)  = GND
  DQ(45)  = M_B_DQ<45>
  VSS(14)  = GND
  DQ(41)  = M_B_DQ<41>
  VSS(13)  = GND
  DQS5N  = M_B_DQS_DN<5>
  DQS5P  = M_B_DQS_DP<5>
  VSS(12)  = GND
  DQ(47)  = M_B_DQ<47>
  VSS(11)  = GND
  DQ(43)  = M_B_DQ<43>
  VSS(10)  = GND
  DQ(53)  = M_B_DQ<53>
  VSS(9)  = GND
  DQ(49)  = M_B_DQ<49>
  VSS(8)  = GND
  DQS6N  = M_B_DQS_DN<6>
  DQS6P  = M_B_DQS_DP<6>
  VSS(7)  = GND
  DQ(55)  = M_B_DQ<55>
  VSS(6)  = GND
  DQ(51)  = M_B_DQ<51>
  VSS(5)  = GND
  DQ(61)  = M_B_DQ<61>
  VSS(4)  = GND
  DQ(57)  = M_B_DQ<57>
  VSS(3)  = GND
  DQS7N  = M_B_DQS_DN<7>
  DQS7P  = M_B_DQS_DP<7>
  VSS(2)  = GND
  DQ(63)  = M_B_DQ<63>
  VSS(1)  = GND
  DQ(59)  = M_B_DQ<59>
  VSS(0)  = GND
  VDDSPD  = PVPP_ABC
  SDA  = SMB_DDR_ABC_VPP_SDA
  VPP(1)  = PVPP_ABC
  VPP(0)  = PVPP_ABC
  VPP(2)  = PVPP_ABC

(kicad_pcb
	(version 20260206)
	(generator "pcbnew")
	(generator_version "10.0")
	(general
		(thickness 1.6)
		(legacy_teardrops no)
	)
	(paper "A4")
	(title_block
		(title "Wiwynn_Tioga_Pass_MB.brd")
		(comment 1 "Tioga Pass / footprint 2988 of 4770 (J6U1), pads 51-100 of 291")
	)
	(layers
		(0 "F.Cu" signal "TOP")
		(4 "In1.Cu" signal "L2GND")
		(6 "In2.Cu" signal "L3")
		(8 "In3.Cu" signal "L4GND")
		(10 "In4.Cu" signal "L5")
		(12 "In5.Cu" signal "L6GND")
		(14 "In6.Cu" signal "L7VCC")
		(16 "In7.Cu" signal "L8VCC")
		(18 "In8.Cu" signal "L9GND")
		(20 "In9.Cu" signal "L10")
		(22 "In10.Cu" signal "L11GND")
		(24 "In11.Cu" signal "L12")
		(26 "In12.Cu" signal "L13GND")
		(2 "B.Cu" signal "BOTTOM")
		(9 "F.Adhes" user "F.Adhesive")
		(11 "B.Adhes" user "B.Adhesive")
		(13 "F.Paste" user "Package Geometry/Pastemask Top")
		(15 "B.Paste" user "Package Geometry/Pastemask Bottom")
		(5 "F.SilkS" user "Ref Des/Silkscreen Top")
		(7 "B.SilkS" user "Ref Des/Silkscreen Bottom")
		(1 "F.Mask" user "Board Geometry/Soldermask Top")
		(3 "B.Mask" user "Board Geometry/Soldermask Bottom")
		(17 "Dwgs.User" user "User.Drawings")
		(19 "Cmts.User" user "User.Comments")
		(21 "Eco1.User" user "User.Eco1")
		(23 "Eco2.User" user "User.Eco2")
		(25 "Edge.Cuts" user "Board Geometry/Outline")
		(27 "Margin" user)
		(31 "F.CrtYd" user "Package Geometry/Place Bound Top")
		(29 "B.CrtYd" user "Package Geometry/Place Bound Bottom")
		(35 "F.Fab" user "Ref Des/Assembly Top")
		(33 "B.Fab" user "Ref Des/Assembly Bottom")
	)
	(footprint ""
		(layer "B.Cu")
		(at 194.700398 -15.222982 90)
		(property "Reference" "J6U1"
			(at 2.530348 39.10711 0)
			(unlocked yes)
			(layer "B.SilkS")
			(effects
				(font
					(size 0.7874 0.5842)
					(thickness 0.1524)
				)
				(justify left mirror)
			)
		)
		(property "Value" ""
			(at 0 0 90)
			(layer "B.Fab")
			(effects
				(font
					(size 1.27 1.27)
				)
				(justify mirror)
			)
		)
		(duplicate_pad_numbers_are_jumpers no)
		(pad "48" smd rect
			(at 0 39.949882 270)
			(size 1.8034 0.508)
			(layers "B.Cu" "B.Mask" "B.Paste")
			(net "GND")
		)
		(pad "49" smd rect
			(at 0 40.80002 270)
			(size 1.8034 0.508)
			(layers "B.Cu" "B.Mask" "B.Paste")
			(net "M_B_ECC<0>")
		)
		(pad "50" smd rect
			(at 0 41.649904 270)
			(size 1.8034 0.508)
			(layers "B.Cu" "B.Mask" "B.Paste")
			(net "GND")
		)
		(pad "51" smd rect
			(at 0 42.500042 270)
			(size 1.8034 0.508)
			(layers "B.Cu" "B.Mask" "B.Paste")
			(net "M_B_DQS_DP<17>")
		)
		(pad "52" smd rect
			(at 0 43.349926 270)
			(size 1.8034 0.508)
			(layers "B.Cu" "B.Mask" "B.Paste")
			(net "M_B_DQS_DN<17>")
		)
		(pad "53" smd rect
			(at 0 44.200064 270)
			(size 1.8034 0.508)
			(layers "B.Cu" "B.Mask" "B.Paste")
			(net "GND")
		)
		(pad "54" smd rect
			(at 0 45.049948 270)
			(size 1.8034 0.508)
			(layers "B.Cu" "B.Mask" "B.Paste")
			(net "M_B_ECC<6>")
		)
		(pad "55" smd rect
			(at 0 45.900086 270)
			(size 1.8034 0.508)
			(layers "B.Cu" "B.Mask" "B.Paste")
			(net "GND")
		)
		(pad "56" smd rect
			(at 0 46.74997 270)
			(size 1.8034 0.508)
			(layers "B.Cu" "B.Mask" "B.Paste")
			(net "M_B_ECC<2>")
		)
		(pad "57" smd rect
			(at 0 47.600108 270)
			(size 1.8034 0.508)
			(layers "B.Cu" "B.Mask" "B.Paste")
			(net "GND")
		)
		(pad "58" smd rect
			(at 0 48.449992 270)
			(size 1.8034 0.508)
			(layers "B.Cu" "B.Mask" "B.Paste")
			(net "M_ABC_RST_N")
		)
		(pad "59" smd rect
			(at 0 49.299876 270)
			(size 1.8034 0.508)
			(layers "B.Cu" "B.Mask" "B.Paste")
			(net "PVDDQ_ABC")
		)
		(pad "60" smd rect
			(at 0 50.150014 270)
			(size 1.8034 0.508)
			(layers "B.Cu" "B.Mask" "B.Paste")
			(net "M_B_CKE<2>")
		)
		(pad "61" smd rect
			(at 0 50.999898 270)
			(size 1.8034 0.508)
			(layers "B.Cu" "B.Mask" "B.Paste")
			(net "PVDDQ_ABC")
		)
		(pad "62" smd rect
			(at 0 51.850036 270)
			(size 1.8034 0.508)
			(layers "B.Cu" "B.Mask" "B.Paste")
			(net "M_B_ACT_N")
		)
		(pad "63" smd rect
			(at 0 52.69992 270)
			(size 1.8034 0.508)
			(layers "B.Cu" "B.Mask" "B.Paste")
			(net "M_B_BG<0>")
		)
		(pad "64" smd rect
			(at 0 53.550058 270)
			(size 1.8034 0.508)
			(layers "B.Cu" "B.Mask" "B.Paste")
			(net "PVDDQ_ABC")
		)
		(pad "65" smd rect
			(at 0 54.399942 270)
			(size 1.8034 0.508)
			(layers "B.Cu" "B.Mask" "B.Paste")
			(net "M_B_MA<12>")
		)
		(pad "66" smd rect
			(at 0 55.25008 270)
			(size 1.8034 0.508)
			(layers "B.Cu" "B.Mask" "B.Paste")
			(net "M_B_MA<9>")
		)
		(pad "67" smd rect
			(at 0 56.099964 270)
			(size 1.8034 0.508)
			(layers "B.Cu" "B.Mask" "B.Paste")
			(net "PVDDQ_ABC")
		)
		(pad "68" smd rect
			(at 0 56.950102 270)
			(size 1.8034 0.508)
			(layers "B.Cu" "B.Mask" "B.Paste")
			(net "M_B_MA<8>")
		)
		(pad "69" smd rect
			(at 0 57.799986 270)
			(size 1.8034 0.508)
			(layers "B.Cu" "B.Mask" "B.Paste")
			(net "M_B_MA<6>")
		)
		(pad "70" smd rect
			(at 0 58.650124 270)
			(size 1.8034 0.508)
			(layers "B.Cu" "B.Mask" "B.Paste")
			(net "PVDDQ_ABC")
		)
		(pad "71" smd rect
			(at 0 59.500008 270)
			(size 1.8034 0.508)
			(layers "B.Cu" "B.Mask" "B.Paste")
			(net "M_B_MA<3>")
		)
		(pad "72" smd rect
			(at 0 60.349892 270)
			(size 1.8034 0.508)
			(layers "B.Cu" "B.Mask" "B.Paste")
			(net "M_B_MA<1>")
		)
		(pad "73" smd rect
			(at 0 61.20003 270)
			(size 1.8034 0.508)
			(layers "B.Cu" "B.Mask" "B.Paste")
			(net "PVDDQ_ABC")
		)
		(pad "74" smd rect
			(at 0 62.049914 270)
			(size 1.8034 0.508)
			(layers "B.Cu" "B.Mask" "B.Paste")
			(net "M_B_CLK_DP<2>")
		)
		(pad "75" smd rect
			(at 0 62.900052 270)
			(size 1.8034 0.508)
			(layers "B.Cu" "B.Mask" "B.Paste")
			(net "M_B_CLK_DN<2>")
		)
		(pad "76" smd rect
			(at 0 63.749936 270)
			(size 1.8034 0.508)
			(layers "B.Cu" "B.Mask" "B.Paste")
			(net "PVDDQ_ABC")
		)
		(pad "77" smd rect
			(at 0 64.600074 270)
			(size 1.8034 0.508)
			(layers "B.Cu" "B.Mask" "B.Paste")
			(net "PVTT_ABC")
		)
		(pad "78" smd rect
			(at 0 70.550024 270)
			(size 1.8034 0.508)
			(layers "B.Cu" "B.Mask" "B.Paste")
			(net "FM_DIMM_EVENT_COD_N")
		)
		(pad "79" smd rect
			(at 0 71.399908 270)
			(size 1.8034 0.508)
			(layers "B.Cu" "B.Mask" "B.Paste")
			(net "M_B_MA<0>")
		)
		(pad "80" smd rect
			(at 0 72.250046 270)
			(size 1.8034 0.508)
			(layers "B.Cu" "B.Mask" "B.Paste")
			(net "PVDDQ_ABC")
		)
		(pad "81" smd rect
			(at 0 73.09993 270)
			(size 1.8034 0.508)
			(layers "B.Cu" "B.Mask" "B.Paste")
			(net "M_B_BA<0>")
		)
		(pad "82" smd rect
			(at 0 73.950068 270)
			(size 1.8034 0.508)
			(layers "B.Cu" "B.Mask" "B.Paste")
			(net "M_B_MA<16>")
		)
		(pad "83" smd rect
			(at 0 74.799952 270)
			(size 1.8034 0.508)
			(layers "B.Cu" "B.Mask" "B.Paste")
			(net "PVDDQ_ABC")
		)
		(pad "84" smd rect
			(at 0 75.65009 270)
			(size 1.8034 0.508)
			(layers "B.Cu" "B.Mask" "B.Paste")
			(net "M_B_CS_N<4>")
		)
		(pad "85" smd rect
			(at 0 76.499974 270)
			(size 1.8034 0.508)
			(layers "B.Cu" "B.Mask" "B.Paste")
			(net "PVDDQ_ABC")
		)
		(pad "86" smd rect
			(at 0 77.350112 270)
			(size 1.8034 0.508)
			(layers "B.Cu" "B.Mask" "B.Paste")
			(net "M_B_MA<15>")
		)
		(pad "87" smd rect
			(at 0 78.199996 270)
			(size 1.8034 0.508)
			(layers "B.Cu" "B.Mask" "B.Paste")
			(net "M_B_ODT<2>")
		)
		(pad "88" smd rect
			(at 0 79.04988 270)
			(size 1.8034 0.508)
			(layers "B.Cu" "B.Mask" "B.Paste")
			(net "PVDDQ_ABC")
		)
		(pad "89" smd rect
			(at 0 79.900018 270)
			(size 1.8034 0.508)
			(layers "B.Cu" "B.Mask" "B.Paste")
			(net "M_B_CS_N<5>")
		)
		(pad "90" smd rect
			(at 0 80.749902 270)
			(size 1.8034 0.508)
			(layers "B.Cu" "B.Mask" "B.Paste")
			(net "PVDDQ_ABC")
		)
		(pad "91" smd rect
			(at 0 81.60004 270)
			(size 1.8034 0.508)
			(layers "B.Cu" "B.Mask" "B.Paste")
			(net "M_B_ODT<3>")
		)
		(pad "92" smd rect
			(at 0 82.449924 270)
			(size 1.8034 0.508)
			(layers "B.Cu" "B.Mask" "B.Paste")
			(net "PVDDQ_ABC")
		)
		(pad "93" smd rect
			(at 0 83.300062 270)
			(size 1.8034 0.508)
			(layers "B.Cu" "B.Mask" "B.Paste")
			(net "M_B_CS_N<6>")
		)
		(pad "94" smd rect
			(at 0 84.149946 270)
			(size 1.8034 0.508)
			(layers "B.Cu" "B.Mask" "B.Paste")
			(net "GND")
		)
		(pad "95" smd rect
			(at 0 85.000084 270)
			(size 1.8034 0.508)
			(layers "B.Cu" "B.Mask" "B.Paste")
			(net "M_B_DQ<36>")
		)
		(pad "96" smd rect
			(at 0 85.849968 270)
			(size 1.8034 0.508)
			(layers "B.Cu" "B.Mask" "B.Paste")
			(net "GND")
		)
		(pad "97" smd rect
			(at 0 86.700106 270)
			(size 1.8034 0.508)
			(layers "B.Cu" "B.Mask" "B.Paste")
			(net "M_B_DQ<32>")
		)
	)
)
